(kicad_pcb
	(version 20260206)
	(generator "pcbnew")
	(generator_version "10.0")
	(general
		(thickness 1.6)
		(legacy_teardrops no)
	)
	(paper "A4")
	(title_block
		(title "Wiwynn_Tioga_Pass_MB.brd")
		(comment 1 "Tioga Pass / footprints 2142-2149 of 4770")
	)
	(layers
		(0 "F.Cu" signal "TOP")
		(4 "In1.Cu" signal "L2GND")
		(6 "In2.Cu" signal "L3")
		(8 "In3.Cu" signal "L4GND")
		(10 "In4.Cu" signal "L5")
		(12 "In5.Cu" signal "L6GND")
		(14 "In6.Cu" signal "L7VCC")
		(16 "In7.Cu" signal "L8VCC")
		(18 "In8.Cu" signal "L9GND")
		(20 "In9.Cu" signal "L10")
		(22 "In10.Cu" signal "L11GND")
		(24 "In11.Cu" signal "L12")
		(26 "In12.Cu" signal "L13GND")
		(2 "B.Cu" signal "BOTTOM")
		(9 "F.Adhes" user "F.Adhesive")
		(11 "B.Adhes" user "B.Adhesive")
		(13 "F.Paste" user "Package Geometry/Pastemask Top")
		(15 "B.Paste" user "Package Geometry/Pastemask Bottom")
		(5 "F.SilkS" user "Ref Des/Silkscreen Top")
		(7 "B.SilkS" user "Ref Des/Silkscreen Bottom")
		(1 "F.Mask" user "Board Geometry/Soldermask Top")
		(3 "B.Mask" user "Board Geometry/Soldermask Bottom")
		(17 "Dwgs.User" user "User.Drawings")
		(19 "Cmts.User" user "User.Comments")
		(21 "Eco1.User" user "User.Eco1")
		(23 "Eco2.User" user "User.Eco2")
		(25 "Edge.Cuts" user "Board Geometry/Outline")
		(27 "Margin" user)
		(31 "F.CrtYd" user "Package Geometry/Place Bound Top")
		(29 "B.CrtYd" user "Package Geometry/Place Bound Bottom")
		(35 "F.Fab" user "Ref Des/Assembly Top")
		(33 "B.Fab" user "Ref Des/Assembly Bottom")
	)
	(footprint ""
		(layer "F.Cu")
		(at -0.786384 -123.210574 90)
		(property "Reference" "CF21"
			(at 0 0 90)
			(layer "F.SilkS")
			(hide yes)
			(effects
				(font
					(size 1.27 1.27)
				)
			)
		)
		(property "Value" "*"
			(at 1.1811 -2.8194 90)
			(unlocked yes)
			(layer "F.Fab")
			(hide yes)
			(effects
				(font
					(size 1.27 1.016)
					(thickness 0.1524)
				)
			)
		)
		(property "Device Type" "SC22P50V2JN-4GP_SMD-BCG-SC22P5A"
			(at 1.1811 -4.3434 90)
			(unlocked yes)
			(layer "F.Fab")
			(hide yes)
			(effects
				(font
					(size 1.27 1.016)
					(thickness 0.1524)
				)
			)
		)
		(duplicate_pad_numbers_are_jumpers no)
		(fp_rect
			(start -0.4318 0.9525)
			(end 0.4318 -0.9525)
			(stroke
				(width 0)
				(type default)
			)
			(fill no)
			(layer "F.CrtYd")
		)
		(fp_rect
			(start -0.4318 0.9525)
			(end 0.4318 -0.9525)
			(stroke
				(width 0)
				(type default)
			)
			(fill no)
			(layer "F.Fab")
		)
		(pad "1" smd custom
			(at 0 -0.4445 90)
			(size 0.1524 0.1524)
			(layers "F.Cu" "F.Mask" "F.Paste")
			(net "VR_PVDDQ_KLM_AIREF1")
			(options
				(clearance outline)
				(anchor circle)
			)
			(primitives
				(gr_poly
					(pts
						(arc
							(start 0.3048 -0.2032)
							(mid 0.275042 -0.275042)
							(end 0.2032 -0.3048)
						)
						(arc
							(start -0.2032 -0.3048)
							(mid -0.275042 -0.275042)
							(end -0.3048 -0.2032)
						)
						(arc
							(start -0.3048 0.2032)
							(mid -0.275042 0.275042)
							(end -0.2032 0.3048)
						)
						(arc
							(start 0.2032 0.3048)
							(mid 0.275042 0.275042)
							(end 0.3048 0.2032)
						)
					)
					(width 0)
					(fill yes)
				)
			)
		)
		(pad "2" smd custom
			(at 0 0.4445 90)
			(size 0.1524 0.1524)
			(layers "F.Cu" "F.Mask" "F.Paste")
			(net "ISENSE_PVDDQ_KLM_PH1_IMON")
			(options
				(clearance outline)
				(anchor circle)
			)
			(primitives
				(gr_poly
					(pts
						(arc
							(start 0.3048 -0.2032)
							(mid 0.275042 -0.275042)
							(end 0.2032 -0.3048)
						)
						(arc
							(start -0.2032 -0.3048)
							(mid -0.275042 -0.275042)
							(end -0.3048 -0.2032)
						)
						(arc
							(start -0.3048 0.2032)
							(mid -0.275042 0.275042)
							(end -0.2032 0.3048)
						)
						(arc
							(start 0.2032 0.3048)
							(mid 0.275042 0.275042)
							(end 0.3048 0.2032)
						)
					)
					(width 0)
					(fill yes)
				)
			)
		)
	)
	(footprint ""
		(layer "F.Cu")
		(at 264.431272 -73.318116)
		(property "Reference" "C5D44"
			(at 0 0 0)
			(layer "F.SilkS")
			(hide yes)
			(effects
				(font
					(size 1.27 1.27)
				)
			)
		)
		(property "Value" ""
			(at 0 0 0)
			(layer "F.Fab")
			(effects
				(font
					(size 1.27 1.27)
				)
			)
		)
		(duplicate_pad_numbers_are_jumpers no)
		(fp_poly
			(pts
				(xy -0.4953 -0.2032) (xy 0.4953 -0.2032) (xy 0.4953 1.6002) (xy -0.4953 1.6002)
			)
			(stroke
				(width 0)
				(type default)
			)
			(fill no)
			(layer "F.CrtYd")
		)
		(fp_line
			(start -0.4953 -0.2032)
			(end 0.4953 -0.2032)
			(stroke
				(width 0.1)
				(type default)
			)
			(layer "F.Fab")
		)
		(fp_line
			(start -0.4953 1.6002)
			(end -0.4953 -0.2032)
			(stroke
				(width 0.1)
				(type default)
			)
			(layer "F.Fab")
		)
		(fp_line
			(start 0.4953 -0.2032)
			(end 0.4953 1.6002)
			(stroke
				(width 0.1)
				(type default)
			)
			(layer "F.Fab")
		)
		(fp_line
			(start 0.4953 1.6002)
			(end -0.4953 1.6002)
			(stroke
				(width 0.1)
				(type default)
			)
			(layer "F.Fab")
		)
		(pad "1" smd rect
			(at 0 0)
			(size 0.762 0.889)
			(layers "F.Cu" "F.Mask" "F.Paste")
			(net "PVCCIN_CPU0")
		)
		(pad "2" smd rect
			(at 0 1.397)
			(size 0.762 0.889)
			(layers "F.Cu" "F.Mask" "F.Paste")
			(net "GND")
		)
		(zone
			(layer "F.Cu")
			(hatch none 0.5)
			(connect_pads
				(clearance 0)
			)
			(min_thickness 0.25)
			(keepout
				(tracks not_allowed)
				(vias allowed)
				(pads allowed)
				(copperpour not_allowed)
				(footprints allowed)
			)
			(placement
				(enabled no)
				(sheetname "")
			)
			(fill
				(thermal_gap 0.5)
				(thermal_bridge_width 0.5)
				(island_removal_mode 0)
			)
			(polygon
				(pts
					(xy 264.050272 -72.873616) (xy 264.812272 -72.873616) (xy 264.812272 -72.365616) (xy 264.050272 -72.365616)
				)
			)
		)
	)
	(footprint ""
		(layer "F.Cu")
		(at 379.815344 -10.941558)
		(property "Reference" "C7G19"
			(at 0 0 0)
			(layer "F.SilkS")
			(hide yes)
			(effects
				(font
					(size 1.27 1.27)
				)
			)
		)
		(property "Value" ""
			(at 0 0 0)
			(layer "F.Fab")
			(effects
				(font
					(size 1.27 1.27)
				)
			)
		)
		(duplicate_pad_numbers_are_jumpers no)
		(fp_rect
			(start -0.3048 0.9906)
			(end 0.3048 -0.1016)
			(stroke
				(width 0)
				(type default)
			)
			(fill no)
			(layer "F.CrtYd")
		)
		(fp_line
			(start -0.3048 -0.1016)
			(end -0.3048 0.9906)
			(stroke
				(width 0.1)
				(type default)
			)
			(layer "F.Fab")
		)
		(fp_line
			(start -0.3048 0.9906)
			(end 0.3048 0.9906)
			(stroke
				(width 0.1)
				(type default)
			)
			(layer "F.Fab")
		)
		(fp_line
			(start 0.3048 -0.1016)
			(end -0.3048 -0.1016)
			(stroke
				(width 0.1)
				(type default)
			)
			(layer "F.Fab")
		)
		(fp_line
			(start 0.3048 0.9906)
			(end 0.3048 -0.1016)
			(stroke
				(width 0.1)
				(type default)
			)
			(layer "F.Fab")
		)
		(pad "1" smd rect
			(at 0 0)
			(size 0.508 0.508)
			(layers "F.Cu" "F.Mask" "F.Paste")
			(net "P3E_CPU0_PE2_SS_TXN<8>")
		)
		(pad "2" smd rect
			(at 0 0.889)
			(size 0.508 0.508)
			(layers "F.Cu" "F.Mask" "F.Paste")
			(net "P3E_CPU0_PE2_SS_C_TXN<8>")
		)
		(zone
			(layer "F.Cu")
			(hatch none 0.5)
			(connect_pads
				(clearance 0)
			)
			(min_thickness 0.25)
			(keepout
				(tracks not_allowed)
				(vias allowed)
				(pads allowed)
				(copperpour not_allowed)
				(footprints allowed)
			)
			(placement
				(enabled no)
				(sheetname "")
			)
			(fill
				(thermal_gap 0.5)
				(thermal_bridge_width 0.5)
				(island_removal_mode 0)
			)
			(polygon
				(pts
					(xy 379.561344 -10.306558) (xy 380.069344 -10.306558) (xy 380.069344 -10.687558) (xy 379.561344 -10.687558)
				)
			)
		)
		(zone
			(layer "F.Cu")
			(hatch none 0.5)
			(connect_pads
				(clearance 0)
			)
			(min_thickness 0.25)
			(keepout
				(tracks allowed)
				(vias not_allowed)
				(pads allowed)
				(copperpour not_allowed)
				(footprints allowed)
			)
			(placement
				(enabled no)
				(sheetname "")
			)
			(fill
				(thermal_gap 0.5)
				(thermal_bridge_width 0.5)
				(island_removal_mode 0)
			)
			(polygon
				(pts
					(xy 379.561344 -10.306558) (xy 380.069344 -10.306558) (xy 380.069344 -10.687558) (xy 379.561344 -10.687558)
				)
			)
		)
	)
	(footprint ""
		(layer "F.Cu")
		(at 4.29895 -13.642594 90)
		(property "Reference" "C1G29"
			(at 0 0 90)
			(layer "F.SilkS")
			(hide yes)
			(effects
				(font
					(size 1.27 1.27)
				)
			)
		)
		(property "Value" ""
			(at 0 0 90)
			(layer "F.Fab")
			(effects
				(font
					(size 1.27 1.27)
				)
			)
		)
		(duplicate_pad_numbers_are_jumpers no)
		(fp_rect
			(start 0.3048 0.9906)
			(end -0.3048 -0.1016)
			(stroke
				(width 0)
				(type default)
			)
			(fill no)
			(layer "F.CrtYd")
		)
		(fp_line
			(start 0.3048 -0.1016)
			(end -0.3048 -0.1016)
			(stroke
				(width 0.1)
				(type default)
			)
			(layer "F.Fab")
		)
		(fp_line
			(start -0.3048 -0.1016)
			(end -0.3048 0.9906)
			(stroke
				(width 0.1)
				(type default)
			)
			(layer "F.Fab")
		)
		(fp_line
			(start 0.3048 0.9906)
			(end 0.3048 -0.1016)
			(stroke
				(width 0.1)
				(type default)
			)
			(layer "F.Fab")
		)
		(fp_line
			(start -0.3048 0.9906)
			(end 0.3048 0.9906)
			(stroke
				(width 0.1)
				(type default)
			)
			(layer "F.Fab")
		)
		(pad "1" smd rect
			(at 0 0 90)
			(size 0.508 0.508)
			(layers "F.Cu" "F.Mask" "F.Paste")
			(net "P5V_STBY")
		)
		(pad "2" smd rect
			(at 0 0.889 90)
			(size 0.508 0.508)
			(layers "F.Cu" "F.Mask" "F.Paste")
			(net "GND")
		)
		(zone
			(layer "F.Cu")
			(hatch none 0.5)
			(connect_pads
				(clearance 0)
			)
			(min_thickness 0.25)
			(keepout
				(tracks not_allowed)
				(vias allowed)
				(pads allowed)
				(copperpour not_allowed)
				(footprints allowed)
			)
			(placement
				(enabled no)
				(sheetname "")
			)
			(fill
				(thermal_gap 0.5)
				(thermal_bridge_width 0.5)
				(island_removal_mode 0)
			)
			(polygon
				(pts
					(xy 4.93395 -13.896594) (xy 4.55295 -13.896594) (xy 4.55295 -13.388594) (xy 4.93395 -13.388594)
				)
			)
		)
		(zone
			(layer "F.Cu")
			(hatch none 0.5)
			(connect_pads
				(clearance 0)
			)
			(min_thickness 0.25)
			(keepout
				(tracks allowed)
				(vias not_allowed)
				(pads allowed)
				(copperpour not_allowed)
				(footprints allowed)
			)
			(placement
				(enabled no)
				(sheetname "")
			)
			(fill
				(thermal_gap 0.5)
				(thermal_bridge_width 0.5)
				(island_removal_mode 0)
			)
			(polygon
				(pts
					(xy 4.93395 -13.896594) (xy 4.55295 -13.896594) (xy 4.55295 -13.388594) (xy 4.93395 -13.388594)
				)
			)
		)
	)
	(footprint ""
		(layer "F.Cu")
		(at 7.69747 -110.891828 90)
		(property "Reference" "C1B19"
			(at -0.8382 -0.67818 90)
			(unlocked yes)
			(layer "F.SilkS")
			(effects
				(font
					(size 0.4064 0.254)
					(thickness 0.1524)
				)
				(justify left)
			)
		)
		(property "Value" ""
			(at 0 0 90)
			(layer "F.Fab")
			(effects
				(font
					(size 1.27 1.27)
				)
			)
		)
		(duplicate_pad_numbers_are_jumpers no)
		(fp_poly
			(pts
				(xy 0.3048 -0.1016) (xy 0.3048 0.9906) (xy -0.3048 0.9906) (xy -0.3048 -0.1016)
			)
			(stroke
				(width 0)
				(type default)
			)
			(fill no)
			(layer "F.CrtYd")
		)
		(fp_line
			(start 0.3048 -0.1016)
			(end -0.3048 -0.1016)
			(stroke
				(width 0.1)
				(type default)
			)
			(layer "F.Fab")
		)
		(fp_line
			(start -0.3048 -0.1016)
			(end -0.3048 0.9906)
			(stroke
				(width 0.1)
				(type default)
			)
			(layer "F.Fab")
		)
		(fp_line
			(start 0.3048 0.9906)
			(end 0.3048 -0.1016)
			(stroke
				(width 0.1)
				(type default)
			)
			(layer "F.Fab")
		)
		(fp_line
			(start -0.3048 0.9906)
			(end 0.3048 0.9906)
			(stroke
				(width 0.1)
				(type default)
			)
			(layer "F.Fab")
		)
		(pad "1" smd rect
			(at 0 0 90)
			(size 0.508 0.508)
			(layers "F.Cu" "F.Mask" "F.Paste")
			(net "P12V_FAN")
		)
		(pad "2" smd rect
			(at 0 0.889 90)
			(size 0.508 0.508)
			(layers "F.Cu" "F.Mask" "F.Paste")
			(net "GND")
		)
		(zone
			(layer "F.Cu")
			(hatch none 0.5)
			(connect_pads
				(clearance 0)
			)
			(min_thickness 0.25)
			(keepout
				(tracks allowed)
				(vias not_allowed)
				(pads allowed)
				(copperpour not_allowed)
				(footprints allowed)
			)
			(placement
				(enabled no)
				(sheetname "")
			)
			(fill
				(thermal_gap 0.5)
				(thermal_bridge_width 0.5)
				(island_removal_mode 0)
			)
			(polygon
				(pts
					(xy 7.95147 -110.637828) (xy 7.95147 -111.145828) (xy 8.33247 -111.145828) (xy 8.33247 -110.637828)
				)
			)
		)
		(zone
			(layer "F.Cu")
			(hatch none 0.5)
			(connect_pads
				(clearance 0)
			)
			(min_thickness 0.25)
			(keepout
				(tracks not_allowed)
				(vias allowed)
				(pads allowed)
				(copperpour not_allowed)
				(footprints allowed)
			)
			(placement
				(enabled no)
				(sheetname "")
			)
			(fill
				(thermal_gap 0.5)
				(thermal_bridge_width 0.5)
				(island_removal_mode 0)
			)
			(polygon
				(pts
					(xy 8.33247 -110.637828) (xy 8.33247 -111.145828) (xy 7.95147 -111.145828) (xy 7.95147 -110.637828)
				)
			)
		)
	)
	(footprint ""
		(layer "F.Cu")
		(at 163.576 -84.328 -90)
		(property "Reference" "R4D11"
			(at 0 0 270)
			(layer "F.SilkS")
			(hide yes)
			(effects
				(font
					(size 1.27 1.27)
				)
			)
		)
		(property "Value" ""
			(at 0 0 270)
			(layer "F.Fab")
			(effects
				(font
					(size 1.27 1.27)
				)
			)
		)
		(duplicate_pad_numbers_are_jumpers no)
		(fp_poly
			(pts
				(xy -0.2794 -0.1016) (xy 0.2794 -0.1016) (xy 0.2794 0.9906) (xy -0.2794 0.9906)
			)
			(stroke
				(width 0)
				(type default)
			)
			(fill no)
			(layer "F.CrtYd")
		)
		(fp_line
			(start -0.2794 0.9906)
			(end 0.2794 0.9906)
			(stroke
				(width 0.1)
				(type default)
			)
			(layer "F.Fab")
		)
		(fp_line
			(start 0.2794 0.9906)
			(end 0.2794 -0.1016)
			(stroke
				(width 0.1)
				(type default)
			)
			(layer "F.Fab")
		)
		(fp_line
			(start -0.2794 -0.1016)
			(end -0.2794 0.9906)
			(stroke
				(width 0.1)
				(type default)
			)
			(layer "F.Fab")
		)
		(fp_line
			(start 0.2794 -0.1016)
			(end -0.2794 -0.1016)
			(stroke
				(width 0.1)
				(type default)
			)
			(layer "F.Fab")
		)
		(pad "1" smd rect
			(at 0 0 270)
			(size 0.508 0.508)
			(layers "F.Cu" "F.Mask" "F.Paste")
			(net "CLK_100M_CPU1_BCLK2_R_DN")
		)
		(pad "2" smd rect
			(at 0 0.889 270)
			(size 0.508 0.508)
			(layers "F.Cu" "F.Mask" "F.Paste")
			(net "CLK_100M_CPU1_BCLK2_DN")
		)
		(zone
			(layer "F.Cu")
			(hatch none 0.5)
			(connect_pads
				(clearance 0)
			)
			(min_thickness 0.25)
			(keepout
				(tracks not_allowed)
				(vias allowed)
				(pads allowed)
				(copperpour not_allowed)
				(footprints allowed)
			)
			(placement
				(enabled no)
				(sheetname "")
			)
			(fill
				(thermal_gap 0.5)
				(thermal_bridge_width 0.5)
				(island_removal_mode 0)
			)
			(polygon
				(pts
					(xy 162.941 -84.582) (xy 162.941 -84.074) (xy 163.322 -84.074) (xy 163.322 -84.582)
				)
			)
		)
		(zone
			(layer "F.Cu")
			(hatch none 0.5)
			(connect_pads
				(clearance 0)
			)
			(min_thickness 0.25)
			(keepout
				(tracks allowed)
				(vias not_allowed)
				(pads allowed)
				(copperpour not_allowed)
				(footprints allowed)
			)
			(placement
				(enabled no)
				(sheetname "")
			)
			(fill
				(thermal_gap 0.5)
				(thermal_bridge_width 0.5)
				(island_removal_mode 0)
			)
			(polygon
				(pts
					(xy 163.322 -84.582) (xy 163.322 -84.074) (xy 162.941 -84.074) (xy 162.941 -84.582)
				)
			)
		)
	)
	(footprint ""
		(layer "F.Cu")
		(at 173.297088 -91.22156 -90)
		(property "Reference" "R4C10"
			(at 0 0 270)
			(layer "F.SilkS")
			(hide yes)
			(effects
				(font
					(size 1.27 1.27)
				)
			)
		)
		(property "Value" ""
			(at 0 0 270)
			(layer "F.Fab")
			(effects
				(font
					(size 1.27 1.27)
				)
			)
		)
		(duplicate_pad_numbers_are_jumpers no)
		(fp_poly
			(pts
				(xy -0.2794 -0.1016) (xy 0.2794 -0.1016) (xy 0.2794 0.9906) (xy -0.2794 0.9906)
			)
			(stroke
				(width 0)
				(type default)
			)
			(fill no)
			(layer "F.CrtYd")
		)
		(fp_line
			(start -0.2794 0.9906)
			(end 0.2794 0.9906)
			(stroke
				(width 0.1)
				(type default)
			)
			(layer "F.Fab")
		)
		(fp_line
			(start 0.2794 0.9906)
			(end 0.2794 -0.1016)
			(stroke
				(width 0.1)
				(type default)
			)
			(layer "F.Fab")
		)
		(fp_line
			(start -0.2794 -0.1016)
			(end -0.2794 0.9906)
			(stroke
				(width 0.1)
				(type default)
			)
			(layer "F.Fab")
		)
		(fp_line
			(start 0.2794 -0.1016)
			(end -0.2794 -0.1016)
			(stroke
				(width 0.1)
				(type default)
			)
			(layer "F.Fab")
		)
		(pad "1" smd rect
			(at 0 0 270)
			(size 0.508 0.508)
			(layers "F.Cu" "F.Mask" "F.Paste")
			(net "PVCCIO_CPU1")
		)
		(pad "2" smd rect
			(at 0 0.889 270)
			(size 0.508 0.508)
			(layers "F.Cu" "F.Mask" "F.Paste")
			(net "PU_CPU1_TSC_SYNC")
		)
		(zone
			(layer "F.Cu")
			(hatch none 0.5)
			(connect_pads
				(clearance 0)
			)
			(min_thickness 0.25)
			(keepout
				(tracks not_allowed)
				(vias allowed)
				(pads allowed)
				(copperpour not_allowed)
				(footprints allowed)
			)
			(placement
				(enabled no)
				(sheetname "")
			)
			(fill
				(thermal_gap 0.5)
				(thermal_bridge_width 0.5)
				(island_removal_mode 0)
			)
			(polygon
				(pts
					(xy 172.662088 -91.47556) (xy 172.662088 -90.96756) (xy 173.043088 -90.96756) (xy 173.043088 -91.47556)
				)
			)
		)
		(zone
			(layer "F.Cu")
			(hatch none 0.5)
			(connect_pads
				(clearance 0)
			)
			(min_thickness 0.25)
			(keepout
				(tracks allowed)
				(vias not_allowed)
				(pads allowed)
				(copperpour not_allowed)
				(footprints allowed)
			)
			(placement
				(enabled no)
				(sheetname "")
			)
			(fill
				(thermal_gap 0.5)
				(thermal_bridge_width 0.5)
				(island_removal_mode 0)
			)
			(polygon
				(pts
					(xy 173.043088 -91.47556) (xy 173.043088 -90.96756) (xy 172.662088 -90.96756) (xy 172.662088 -91.47556)
				)
			)
		)
	)
	(footprint ""
		(layer "F.Cu")
		(at 368.554 -109.601 90)
		(property "Reference" "C7C3"
			(at 0 0 90)
			(layer "F.SilkS")
			(hide yes)
			(effects
				(font
					(size 1.27 1.27)
				)
			)
		)
		(property "Value" ""
			(at 0 0 90)
			(layer "F.Fab")
			(effects
				(font
					(size 1.27 1.27)
				)
			)
		)
		(duplicate_pad_numbers_are_jumpers no)
		(fp_poly
			(pts
				(xy 0.3048 -0.1016) (xy 0.3048 0.9906) (xy -0.3048 0.9906) (xy -0.3048 -0.1016)
			)
			(stroke
				(width 0)
				(type default)
			)
			(fill no)
			(layer "F.CrtYd")
		)
		(fp_line
			(start 0.3048 -0.1016)
			(end -0.3048 -0.1016)
			(stroke
				(width 0.1)
				(type default)
			)
			(layer "F.Fab")
		)
		(fp_line
			(start -0.3048 -0.1016)
			(end -0.3048 0.9906)
			(stroke
				(width 0.1)
				(type default)
			)
			(layer "F.Fab")
		)
		(fp_line
			(start 0.3048 0.9906)
			(end 0.3048 -0.1016)
			(stroke
				(width 0.1)
				(type default)
			)
			(layer "F.Fab")
		)
		(fp_line
			(start -0.3048 0.9906)
			(end 0.3048 0.9906)
			(stroke
				(width 0.1)
				(type default)
			)
			(layer "F.Fab")
		)
		(pad "1" smd rect
			(at 0 0 90)
			(size 0.508 0.508)
			(layers "F.Cu" "F.Mask" "F.Paste")
			(net "DMI_CPU0_PCH_TX_DN<0>")
		)
		(pad "2" smd rect
			(at 0 0.889 90)
			(size 0.508 0.508)
			(layers "F.Cu" "F.Mask" "F.Paste")
			(net "DMI_CPU0_PCH_TX_C_DN<0>")
		)
		(zone
			(layer "F.Cu")
			(hatch none 0.5)
			(connect_pads
				(clearance 0)
			)
			(min_thickness 0.25)
			(keepout
				(tracks allowed)
				(vias not_allowed)
				(pads allowed)
				(copperpour not_allowed)
				(footprints allowed)
			)
			(placement
				(enabled no)
				(sheetname "")
			)
			(fill
				(thermal_gap 0.5)
				(thermal_bridge_width 0.5)
				(island_removal_mode 0)
			)
			(polygon
				(pts
					(xy 368.808 -109.347) (xy 368.808 -109.855) (xy 369.189 -109.855) (xy 369.189 -109.347)
				)
			)
		)
		(zone
			(layer "F.Cu")
			(hatch none 0.5)
			(connect_pads
				(clearance 0)
			)
			(min_thickness 0.25)
			(keepout
				(tracks not_allowed)
				(vias allowed)
				(pads allowed)
				(copperpour not_allowed)
				(footprints allowed)
			)
			(placement
				(enabled no)
				(sheetname "")
			)
			(fill
				(thermal_gap 0.5)
				(thermal_bridge_width 0.5)
				(island_removal_mode 0)
			)
			(polygon
				(pts
					(xy 369.189 -109.347) (xy 369.189 -109.855) (xy 368.808 -109.855) (xy 368.808 -109.347)
				)
			)
		)
	)
)
